(kicad_pcb
	(version 20260206)
	(generator "pcbnew")
	(generator_version "10.0")
	(general
		(thickness 1.6)
		(legacy_teardrops no)
	)
	(paper "A4")
	(title_block
		(title "12092022_DA0F0TMDCD0_F0T_Management_Board_D_brd_V3_OCP.brd")
		(comment 1 "Grand Teton / footprints 294-299 of 1440")
	)
	(layers
		(0 "F.Cu" signal "TOP")
		(4 "In1.Cu" signal "GND")
		(6 "In2.Cu" signal "IN1")
		(8 "In3.Cu" signal "GND1")
		(10 "In4.Cu" signal "IN2")
		(12 "In5.Cu" signal "VCC")
		(14 "In6.Cu" signal "VCC1")
		(16 "In7.Cu" signal "IN3")
		(18 "In8.Cu" signal "GND2")
		(20 "In9.Cu" signal "IN4")
		(22 "In10.Cu" signal "GND3")
		(2 "B.Cu" signal "BOTTOM")
		(9 "F.Adhes" user "F.Adhesive")
		(11 "B.Adhes" user "B.Adhesive")
		(13 "F.Paste" user "Package Geometry/Pastemask Top")
		(15 "B.Paste" user "Package Geometry/Pastemask Bottom")
		(5 "F.SilkS" user "Ref Des/Silkscreen Top")
		(7 "B.SilkS" user "Ref Des/Silkscreen Bottom")
		(1 "F.Mask" user "Board Geometry/Soldermask Top")
		(3 "B.Mask" user "Board Geometry/Soldermask Bottom")
		(17 "Dwgs.User" user "User.Drawings")
		(19 "Cmts.User" user "User.Comments")
		(21 "Eco1.User" user "User.Eco1")
		(23 "Eco2.User" user "User.Eco2")
		(25 "Edge.Cuts" user "Board Geometry/Outline")
		(27 "Margin" user)
		(31 "F.CrtYd" user "Package Geometry/Place Bound Top")
		(29 "B.CrtYd" user "Package Geometry/Place Bound Bottom")
		(35 "F.Fab" user "Ref Des/Assembly Top")
		(33 "B.Fab" user "Ref Des/Assembly Bottom")
	)
	(footprint ""
		(layer "F.Cu")
		(at 16.637 -46.3042 90)
		(property "Reference" "C304"
			(at 0 0 90)
			(layer "F.SilkS")
			(hide yes)
			(effects
				(font
					(size 1.27 1.27)
				)
			)
		)
		(property "Value" ""
			(at 0 0 90)
			(layer "F.Fab")
			(effects
				(font
					(size 1.27 1.27)
				)
			)
		)
		(duplicate_pad_numbers_are_jumpers no)
		(fp_line
			(start 0.7874 -0.4064)
			(end 0.7874 0.4064)
			(stroke
				(width 0.1524)
				(type default)
			)
			(layer "F.SilkS")
		)
		(fp_line
			(start -0.7874 -0.4064)
			(end 0.7874 -0.4064)
			(stroke
				(width 0.1524)
				(type default)
			)
			(layer "F.SilkS")
		)
		(fp_line
			(start 0.7874 0.4064)
			(end -0.7874 0.4064)
			(stroke
				(width 0.1524)
				(type default)
			)
			(layer "F.SilkS")
		)
		(fp_line
			(start -0.7874 0.4064)
			(end -0.7874 -0.4064)
			(stroke
				(width 0.1524)
				(type default)
			)
			(layer "F.SilkS")
		)
		(fp_line
			(start -0.12065 -0.305054)
			(end -0.12065 -0.2794)
			(stroke
				(width 0.1)
				(type default)
			)
			(layer "F.Fab")
		)
		(fp_line
			(start -0.67945 -0.305054)
			(end -0.12065 -0.305054)
			(stroke
				(width 0.1)
				(type default)
			)
			(layer "F.Fab")
		)
		(fp_line
			(start 0.67945 -0.3048)
			(end 0.67945 0.3048)
			(stroke
				(width 0.1)
				(type default)
			)
			(layer "F.Fab")
		)
		(fp_line
			(start 0.12065 -0.3048)
			(end 0.67945 -0.3048)
			(stroke
				(width 0.1)
				(type default)
			)
			(layer "F.Fab")
		)
		(fp_line
			(start 0.12065 -0.2794)
			(end 0.12065 -0.3048)
			(stroke
				(width 0.1)
				(type default)
			)
			(layer "F.Fab")
		)
		(fp_line
			(start -0.12065 -0.2794)
			(end 0.12065 -0.2794)
			(stroke
				(width 0.1)
				(type default)
			)
			(layer "F.Fab")
		)
		(fp_line
			(start 0.120396 0.2794)
			(end -0.12065 0.2794)
			(stroke
				(width 0.1)
				(type default)
			)
			(layer "F.Fab")
		)
		(fp_line
			(start -0.12065 0.2794)
			(end -0.12065 0.3048)
			(stroke
				(width 0.1)
				(type default)
			)
			(layer "F.Fab")
		)
		(fp_line
			(start 0.67945 0.3048)
			(end 0.120396 0.3048)
			(stroke
				(width 0.1)
				(type default)
			)
			(layer "F.Fab")
		)
		(fp_line
			(start 0.120396 0.3048)
			(end 0.120396 0.2794)
			(stroke
				(width 0.1)
				(type default)
			)
			(layer "F.Fab")
		)
		(fp_line
			(start -0.12065 0.3048)
			(end -0.67945 0.3048)
			(stroke
				(width 0.1)
				(type default)
			)
			(layer "F.Fab")
		)
		(fp_line
			(start -0.67945 0.3048)
			(end -0.67945 -0.305054)
			(stroke
				(width 0.1)
				(type default)
			)
			(layer "F.Fab")
		)
		(pad "1" smd circle
			(at -0.40005 0 90)
			(size 0 0)
			(layers "F.Cu" "F.Mask" "F.Paste")
			(net "P3V3_AUX")
		)
		(pad "2" smd circle
			(at 0.40005 0 90)
			(size 0 0)
			(layers "F.Cu" "F.Mask" "F.Paste")
			(net "GND")
		)
	)
	(footprint ""
		(layer "F.Cu")
		(at 37.063172 -83.816952 90)
		(property "Reference" "R648"
			(at 0 0 90)
			(layer "F.SilkS")
			(hide yes)
			(effects
				(font
					(size 1.27 1.27)
				)
			)
		)
		(property "Value" ""
			(at 0 0 90)
			(layer "F.Fab")
			(effects
				(font
					(size 1.27 1.27)
				)
			)
		)
		(duplicate_pad_numbers_are_jumpers no)
		(fp_line
			(start 0.7874 -0.4064)
			(end 0.7874 0.4064)
			(stroke
				(width 0.1524)
				(type default)
			)
			(layer "F.SilkS")
		)
		(fp_line
			(start -0.7874 -0.4064)
			(end 0.7874 -0.4064)
			(stroke
				(width 0.1524)
				(type default)
			)
			(layer "F.SilkS")
		)
		(fp_line
			(start 0.7874 0.4064)
			(end -0.7874 0.4064)
			(stroke
				(width 0.1524)
				(type default)
			)
			(layer "F.SilkS")
		)
		(fp_line
			(start -0.7874 0.4064)
			(end -0.7874 -0.4064)
			(stroke
				(width 0.1524)
				(type default)
			)
			(layer "F.SilkS")
		)
		(fp_line
			(start -0.12065 -0.305054)
			(end -0.12065 -0.2794)
			(stroke
				(width 0.1)
				(type default)
			)
			(layer "F.Fab")
		)
		(fp_line
			(start -0.67945 -0.305054)
			(end -0.12065 -0.305054)
			(stroke
				(width 0.1)
				(type default)
			)
			(layer "F.Fab")
		)
		(fp_line
			(start 0.67945 -0.3048)
			(end 0.67945 0.3048)
			(stroke
				(width 0.1)
				(type default)
			)
			(layer "F.Fab")
		)
		(fp_line
			(start 0.12065 -0.3048)
			(end 0.67945 -0.3048)
			(stroke
				(width 0.1)
				(type default)
			)
			(layer "F.Fab")
		)
		(fp_line
			(start 0.12065 -0.2794)
			(end 0.12065 -0.3048)
			(stroke
				(width 0.1)
				(type default)
			)
			(layer "F.Fab")
		)
		(fp_line
			(start -0.12065 -0.2794)
			(end 0.12065 -0.2794)
			(stroke
				(width 0.1)
				(type default)
			)
			(layer "F.Fab")
		)
		(fp_line
			(start 0.120396 0.2794)
			(end -0.12065 0.2794)
			(stroke
				(width 0.1)
				(type default)
			)
			(layer "F.Fab")
		)
		(fp_line
			(start -0.12065 0.2794)
			(end -0.12065 0.3048)
			(stroke
				(width 0.1)
				(type default)
			)
			(layer "F.Fab")
		)
		(fp_line
			(start 0.67945 0.3048)
			(end 0.120396 0.3048)
			(stroke
				(width 0.1)
				(type default)
			)
			(layer "F.Fab")
		)
		(fp_line
			(start 0.120396 0.3048)
			(end 0.120396 0.2794)
			(stroke
				(width 0.1)
				(type default)
			)
			(layer "F.Fab")
		)
		(fp_line
			(start -0.12065 0.3048)
			(end -0.67945 0.3048)
			(stroke
				(width 0.1)
				(type default)
			)
			(layer "F.Fab")
		)
		(fp_line
			(start -0.67945 0.3048)
			(end -0.67945 -0.305054)
			(stroke
				(width 0.1)
				(type default)
			)
			(layer "F.Fab")
		)
		(pad "1" smd circle
			(at -0.40005 0 90)
			(size 0 0)
			(layers "F.Cu" "F.Mask" "F.Paste")
			(net "EMMC_DT1_R")
		)
		(pad "2" smd circle
			(at 0.40005 0 90)
			(size 0 0)
			(layers "F.Cu" "F.Mask" "F.Paste")
			(net "BMC_EMMC_DT1")
		)
	)
	(footprint ""
		(layer "F.Cu")
		(at 69.005196 -37.288216 -90)
		(property "Reference" "C52"
			(at 0 0 270)
			(layer "F.SilkS")
			(hide yes)
			(effects
				(font
					(size 1.27 1.27)
				)
			)
		)
		(property "Value" ""
			(at 0 0 270)
			(layer "F.Fab")
			(effects
				(font
					(size 1.27 1.27)
				)
			)
		)
		(duplicate_pad_numbers_are_jumpers no)
		(fp_line
			(start -0.7874 0.4064)
			(end -0.7874 -0.4064)
			(stroke
				(width 0.1524)
				(type default)
			)
			(layer "F.SilkS")
		)
		(fp_line
			(start 0.7874 0.4064)
			(end -0.7874 0.4064)
			(stroke
				(width 0.1524)
				(type default)
			)
			(layer "F.SilkS")
		)
		(fp_line
			(start -0.7874 -0.4064)
			(end 0.7874 -0.4064)
			(stroke
				(width 0.1524)
				(type default)
			)
			(layer "F.SilkS")
		)
		(fp_line
			(start 0.7874 -0.4064)
			(end 0.7874 0.4064)
			(stroke
				(width 0.1524)
				(type default)
			)
			(layer "F.SilkS")
		)
		(fp_line
			(start -0.67945 0.3048)
			(end -0.67945 -0.305054)
			(stroke
				(width 0.1)
				(type default)
			)
			(layer "F.Fab")
		)
		(fp_line
			(start -0.12065 0.3048)
			(end -0.67945 0.3048)
			(stroke
				(width 0.1)
				(type default)
			)
			(layer "F.Fab")
		)
		(fp_line
			(start 0.120396 0.3048)
			(end 0.120396 0.2794)
			(stroke
				(width 0.1)
				(type default)
			)
			(layer "F.Fab")
		)
		(fp_line
			(start 0.67945 0.3048)
			(end 0.120396 0.3048)
			(stroke
				(width 0.1)
				(type default)
			)
			(layer "F.Fab")
		)
		(fp_line
			(start -0.12065 0.2794)
			(end -0.12065 0.3048)
			(stroke
				(width 0.1)
				(type default)
			)
			(layer "F.Fab")
		)
		(fp_line
			(start 0.120396 0.2794)
			(end -0.12065 0.2794)
			(stroke
				(width 0.1)
				(type default)
			)
			(layer "F.Fab")
		)
		(fp_line
			(start -0.12065 -0.2794)
			(end 0.12065 -0.2794)
			(stroke
				(width 0.1)
				(type default)
			)
			(layer "F.Fab")
		)
		(fp_line
			(start 0.12065 -0.2794)
			(end 0.12065 -0.3048)
			(stroke
				(width 0.1)
				(type default)
			)
			(layer "F.Fab")
		)
		(fp_line
			(start 0.12065 -0.3048)
			(end 0.67945 -0.3048)
			(stroke
				(width 0.1)
				(type default)
			)
			(layer "F.Fab")
		)
		(fp_line
			(start 0.67945 -0.3048)
			(end 0.67945 0.3048)
			(stroke
				(width 0.1)
				(type default)
			)
			(layer "F.Fab")
		)
		(fp_line
			(start -0.67945 -0.305054)
			(end -0.12065 -0.305054)
			(stroke
				(width 0.1)
				(type default)
			)
			(layer "F.Fab")
		)
		(fp_line
			(start -0.12065 -0.305054)
			(end -0.12065 -0.2794)
			(stroke
				(width 0.1)
				(type default)
			)
			(layer "F.Fab")
		)
		(pad "1" smd circle
			(at -0.40005 0 270)
			(size 0 0)
			(layers "F.Cu" "F.Mask" "F.Paste")
			(net "P1V0_STBY_PLAVDD")
		)
		(pad "2" smd circle
			(at 0.40005 0 270)
			(size 0 0)
			(layers "F.Cu" "F.Mask" "F.Paste")
			(net "GND")
		)
	)
	(footprint ""
		(layer "F.Cu")
		(at 12.319 -88.392 180)
		(property "Reference" "R526"
			(at 0 0 180)
			(layer "F.SilkS")
			(hide yes)
			(effects
				(font
					(size 1.27 1.27)
				)
			)
		)
		(property "Value" ""
			(at 0 0 180)
			(layer "F.Fab")
			(effects
				(font
					(size 1.27 1.27)
				)
			)
		)
		(duplicate_pad_numbers_are_jumpers no)
		(fp_line
			(start 0.7874 0.4064)
			(end -0.7874 0.4064)
			(stroke
				(width 0.1524)
				(type default)
			)
			(layer "F.SilkS")
		)
		(fp_line
			(start 0.7874 -0.4064)
			(end 0.7874 0.4064)
			(stroke
				(width 0.1524)
				(type default)
			)
			(layer "F.SilkS")
		)
		(fp_line
			(start -0.7874 0.4064)
			(end -0.7874 -0.4064)
			(stroke
				(width 0.1524)
				(type default)
			)
			(layer "F.SilkS")
		)
		(fp_line
			(start -0.7874 -0.4064)
			(end 0.7874 -0.4064)
			(stroke
				(width 0.1524)
				(type default)
			)
			(layer "F.SilkS")
		)
		(fp_line
			(start 0.67945 0.3048)
			(end 0.120396 0.3048)
			(stroke
				(width 0.1)
				(type default)
			)
			(layer "F.Fab")
		)
		(fp_line
			(start 0.67945 -0.3048)
			(end 0.67945 0.3048)
			(stroke
				(width 0.1)
				(type default)
			)
			(layer "F.Fab")
		)
		(fp_line
			(start 0.12065 -0.2794)
			(end 0.12065 -0.3048)
			(stroke
				(width 0.1)
				(type default)
			)
			(layer "F.Fab")
		)
		(fp_line
			(start 0.12065 -0.3048)
			(end 0.67945 -0.3048)
			(stroke
				(width 0.1)
				(type default)
			)
			(layer "F.Fab")
		)
		(fp_line
			(start 0.120396 0.3048)
			(end 0.120396 0.2794)
			(stroke
				(width 0.1)
				(type default)
			)
			(layer "F.Fab")
		)
		(fp_line
			(start 0.120396 0.2794)
			(end -0.12065 0.2794)
			(stroke
				(width 0.1)
				(type default)
			)
			(layer "F.Fab")
		)
		(fp_line
			(start -0.12065 0.3048)
			(end -0.67945 0.3048)
			(stroke
				(width 0.1)
				(type default)
			)
			(layer "F.Fab")
		)
		(fp_line
			(start -0.12065 0.2794)
			(end -0.12065 0.3048)
			(stroke
				(width 0.1)
				(type default)
			)
			(layer "F.Fab")
		)
		(fp_line
			(start -0.12065 -0.2794)
			(end 0.12065 -0.2794)
			(stroke
				(width 0.1)
				(type default)
			)
			(layer "F.Fab")
		)
		(fp_line
			(start -0.12065 -0.305054)
			(end -0.12065 -0.2794)
			(stroke
				(width 0.1)
				(type default)
			)
			(layer "F.Fab")
		)
		(fp_line
			(start -0.67945 0.3048)
			(end -0.67945 -0.305054)
			(stroke
				(width 0.1)
				(type default)
			)
			(layer "F.Fab")
		)
		(fp_line
			(start -0.67945 -0.305054)
			(end -0.12065 -0.305054)
			(stroke
				(width 0.1)
				(type default)
			)
			(layer "F.Fab")
		)
		(pad "1" smd circle
			(at -0.40005 0 180)
			(size 0 0)
			(layers "F.Cu" "F.Mask" "F.Paste")
			(net "BMC_CPLD_GPIO_7_R2")
		)
		(pad "2" smd circle
			(at 0.40005 0 180)
			(size 0 0)
			(layers "F.Cu" "F.Mask" "F.Paste")
			(net "BMC_CPLD_GPIO_7")
		)
	)
	(footprint ""
		(layer "F.Cu")
		(at 57.023 -76.3524 180)
		(property "Reference" "R182"
			(at 0 0 180)
			(layer "F.SilkS")
			(hide yes)
			(effects
				(font
					(size 1.27 1.27)
				)
			)
		)
		(property "Value" ""
			(at 0 0 180)
			(layer "F.Fab")
			(effects
				(font
					(size 1.27 1.27)
				)
			)
		)
		(duplicate_pad_numbers_are_jumpers no)
		(fp_line
			(start 0.7874 0.4064)
			(end -0.7874 0.4064)
			(stroke
				(width 0.1524)
				(type default)
			)
			(layer "F.SilkS")
		)
		(fp_line
			(start 0.7874 -0.4064)
			(end 0.7874 0.4064)
			(stroke
				(width 0.1524)
				(type default)
			)
			(layer "F.SilkS")
		)
		(fp_line
			(start -0.7874 0.4064)
			(end -0.7874 -0.4064)
			(stroke
				(width 0.1524)
				(type default)
			)
			(layer "F.SilkS")
		)
		(fp_line
			(start -0.7874 -0.4064)
			(end 0.7874 -0.4064)
			(stroke
				(width 0.1524)
				(type default)
			)
			(layer "F.SilkS")
		)
		(fp_line
			(start 0.67945 0.3048)
			(end 0.120396 0.3048)
			(stroke
				(width 0.1)
				(type default)
			)
			(layer "F.Fab")
		)
		(fp_line
			(start 0.67945 -0.3048)
			(end 0.67945 0.3048)
			(stroke
				(width 0.1)
				(type default)
			)
			(layer "F.Fab")
		)
		(fp_line
			(start 0.12065 -0.2794)
			(end 0.12065 -0.3048)
			(stroke
				(width 0.1)
				(type default)
			)
			(layer "F.Fab")
		)
		(fp_line
			(start 0.12065 -0.3048)
			(end 0.67945 -0.3048)
			(stroke
				(width 0.1)
				(type default)
			)
			(layer "F.Fab")
		)
		(fp_line
			(start 0.120396 0.3048)
			(end 0.120396 0.2794)
			(stroke
				(width 0.1)
				(type default)
			)
			(layer "F.Fab")
		)
		(fp_line
			(start 0.120396 0.2794)
			(end -0.12065 0.2794)
			(stroke
				(width 0.1)
				(type default)
			)
			(layer "F.Fab")
		)
		(fp_line
			(start -0.12065 0.3048)
			(end -0.67945 0.3048)
			(stroke
				(width 0.1)
				(type default)
			)
			(layer "F.Fab")
		)
		(fp_line
			(start -0.12065 0.2794)
			(end -0.12065 0.3048)
			(stroke
				(width 0.1)
				(type default)
			)
			(layer "F.Fab")
		)
		(fp_line
			(start -0.12065 -0.2794)
			(end 0.12065 -0.2794)
			(stroke
				(width 0.1)
				(type default)
			)
			(layer "F.Fab")
		)
		(fp_line
			(start -0.12065 -0.305054)
			(end -0.12065 -0.2794)
			(stroke
				(width 0.1)
				(type default)
			)
			(layer "F.Fab")
		)
		(fp_line
			(start -0.67945 0.3048)
			(end -0.67945 -0.305054)
			(stroke
				(width 0.1)
				(type default)
			)
			(layer "F.Fab")
		)
		(fp_line
			(start -0.67945 -0.305054)
			(end -0.12065 -0.305054)
			(stroke
				(width 0.1)
				(type default)
			)
			(layer "F.Fab")
		)
		(pad "1" smd circle
			(at -0.40005 0 180)
			(size 0 0)
			(layers "F.Cu" "F.Mask" "F.Paste")
			(net "GND")
		)
		(pad "2" smd circle
			(at 0.40005 0 180)
			(size 0 0)
			(layers "F.Cu" "F.Mask" "F.Paste")
			(net "FLASH_LATCH_D")
		)
	)
	(footprint ""
		(layer "F.Cu")
		(at 48.6156 -30.867604 90)
		(property "Reference" "R245"
			(at 0 0 90)
			(layer "F.SilkS")
			(hide yes)
			(effects
				(font
					(size 1.27 1.27)
				)
			)
		)
		(property "Value" ""
			(at 0 0 90)
			(layer "F.Fab")
			(effects
				(font
					(size 1.27 1.27)
				)
			)
		)
		(duplicate_pad_numbers_are_jumpers no)
		(fp_line
			(start 0.7874 -0.4064)
			(end 0.7874 0.4064)
			(stroke
				(width 0.1524)
				(type default)
			)
			(layer "F.SilkS")
		)
		(fp_line
			(start -0.7874 -0.4064)
			(end 0.7874 -0.4064)
			(stroke
				(width 0.1524)
				(type default)
			)
			(layer "F.SilkS")
		)
		(fp_line
			(start 0.7874 0.4064)
			(end -0.7874 0.4064)
			(stroke
				(width 0.1524)
				(type default)
			)
			(layer "F.SilkS")
		)
		(fp_line
			(start -0.7874 0.4064)
			(end -0.7874 -0.4064)
			(stroke
				(width 0.1524)
				(type default)
			)
			(layer "F.SilkS")
		)
		(fp_line
			(start -0.12065 -0.305054)
			(end -0.12065 -0.2794)
			(stroke
				(width 0.1)
				(type default)
			)
			(layer "F.Fab")
		)
		(fp_line
			(start -0.67945 -0.305054)
			(end -0.12065 -0.305054)
			(stroke
				(width 0.1)
				(type default)
			)
			(layer "F.Fab")
		)
		(fp_line
			(start 0.67945 -0.3048)
			(end 0.67945 0.3048)
			(stroke
				(width 0.1)
				(type default)
			)
			(layer "F.Fab")
		)
		(fp_line
			(start 0.12065 -0.3048)
			(end 0.67945 -0.3048)
			(stroke
				(width 0.1)
				(type default)
			)
			(layer "F.Fab")
		)
		(fp_line
			(start 0.12065 -0.2794)
			(end 0.12065 -0.3048)
			(stroke
				(width 0.1)
				(type default)
			)
			(layer "F.Fab")
		)
		(fp_line
			(start -0.12065 -0.2794)
			(end 0.12065 -0.2794)
			(stroke
				(width 0.1)
				(type default)
			)
			(layer "F.Fab")
		)
		(fp_line
			(start 0.120396 0.2794)
			(end -0.12065 0.2794)
			(stroke
				(width 0.1)
				(type default)
			)
			(layer "F.Fab")
		)
		(fp_line
			(start -0.12065 0.2794)
			(end -0.12065 0.3048)
			(stroke
				(width 0.1)
				(type default)
			)
			(layer "F.Fab")
		)
		(fp_line
			(start 0.67945 0.3048)
			(end 0.120396 0.3048)
			(stroke
				(width 0.1)
				(type default)
			)
			(layer "F.Fab")
		)
		(fp_line
			(start 0.120396 0.3048)
			(end 0.120396 0.2794)
			(stroke
				(width 0.1)
				(type default)
			)
			(layer "F.Fab")
		)
		(fp_line
			(start -0.12065 0.3048)
			(end -0.67945 0.3048)
			(stroke
				(width 0.1)
				(type default)
			)
			(layer "F.Fab")
		)
		(fp_line
			(start -0.67945 0.3048)
			(end -0.67945 -0.305054)
			(stroke
				(width 0.1)
				(type default)
			)
			(layer "F.Fab")
		)
		(pad "1" smd circle
			(at -0.40005 0 90)
			(size 0 0)
			(layers "F.Cu" "F.Mask" "F.Paste")
			(net "P3V3_AUX")
		)
		(pad "2" smd circle
			(at 0.40005 0 90)
			(size 0 0)
			(layers "F.Cu" "F.Mask" "F.Paste")
			(net "SMB_BMC_MM1_SDA")
		)
	)
)
